(kicad_pcb
	(version 20241229)
	(generator "pcbnew")
	(generator_version "9.0")
	(general
		(thickness 1.552)
		(legacy_teardrops no)
	)
	(paper "A4")
	(title_block
		(date "2023-07-25")
		(rev "1.1.4")
		(comment 9 "footprint 14 of 379 (U11), pads 246-256 of 256")
	)
	(layers
		(0 "F.Cu" signal)
		(4 "In1.Cu" signal)
		(6 "In2.Cu" signal)
		(8 "In3.Cu" signal)
		(10 "In4.Cu" signal)
		(12 "In5.Cu" signal)
		(14 "In6.Cu" signal)
		(2 "B.Cu" signal)
		(9 "F.Adhes" user "F.Adhesive")
		(11 "B.Adhes" user "B.Adhesive")
		(13 "F.Paste" user)
		(15 "B.Paste" user)
		(5 "F.SilkS" user "F.Silkscreen")
		(7 "B.SilkS" user "B.Silkscreen")
		(1 "F.Mask" user)
		(3 "B.Mask" user)
		(17 "Dwgs.User" user "User.Drawings")
		(19 "Cmts.User" user "User.Comments")
		(21 "Eco1.User" user "User.Eco1")
		(23 "Eco2.User" user "User.Eco2")
		(25 "Edge.Cuts" user)
		(27 "Margin" user)
		(31 "F.CrtYd" user "F.Courtyard")
		(29 "B.CrtYd" user "B.Courtyard")
		(35 "F.Fab" user)
		(33 "B.Fab" user)
	)
	(footprint "antmicro-footprints:BGA-256_14x14mm_Layout16x16_P0.8mm"
		(locked yes)
		(layer "F.Cu")
		(at 126.3 90.3 180)
		(property "Reference" "U11"
			(at 0 -8 180)
			(layer "F.SilkS")
			(effects
				(font
					(size 0.7 0.7)
					(thickness 0.15)
				)
				(justify left bottom)
			)
		)
		(property "Value" "LIFCL-40-9BG256C"
			(at -8 8.55 180)
			(layer "F.Fab")
			(effects
				(font
					(size 0.7 0.7)
					(thickness 0.15)
				)
				(justify left bottom)
			)
		)
		(property "Datasheet" "https://www.latticesemi.com/-/media/LatticeSemi/Documents/DataSheets/CrossLink/FPGA-DS-02007-2-1-CrossLink-Family-Data-Sheet.ashx?document_id=51662"
			(at 0 0 180)
			(layer "F.Fab")
			(hide yes)
			(effects
				(font
					(size 1.27 1.27)
					(thickness 0.15)
				)
			)
		)
		(property "Description" "CrossLink-NX™ Field Programmable Gate Array 256-LFBGA"
			(at 0 0 180)
			(layer "F.Fab")
			(hide yes)
			(effects
				(font
					(size 1.27 1.27)
					(thickness 0.15)
				)
			)
		)
		(property "Author" "Antmicro"
			(at 252.6 180.6 0)
			(layer "F.Fab")
			(hide yes)
			(effects
				(font
					(size 1 1)
					(thickness 0.15)
				)
			)
		)
		(property "License" "Apache-2.0"
			(at 252.6 180.6 0)
			(layer "F.Fab")
			(hide yes)
			(effects
				(font
					(size 1 1)
					(thickness 0.15)
				)
			)
		)
		(property "MPN" "LIFCL-40-9BG256C"
			(at 252.6 180.6 0)
			(layer "F.Fab")
			(hide yes)
			(effects
				(font
					(size 1 1)
					(thickness 0.15)
				)
			)
		)
		(property "Manufacturer" "Lattice Semiconductor"
			(at 252.6 180.6 0)
			(layer "F.Fab")
			(hide yes)
			(effects
				(font
					(size 1 1)
					(thickness 0.15)
				)
			)
		)
		(sheetname "/DDR3/")
		(sheetfile "ddr3.kicad_sch")
		(attr smd)
		(pad "T6" smd circle
			(at -2 6 180)
			(size 0.45 0.45)
			(layers "F.Cu" "F.Mask" "F.Paste")
			(net 233 "/DDR3/DDR3_DQ1")
			(pinfunction "PB28A")
			(pintype "bidirectional")
		)
		(pad "T7" smd circle
			(at -1.2 6 180)
			(size 0.45 0.45)
			(layers "F.Cu" "F.Mask" "F.Paste")
			(net 166 "/DDR3/DDR3_ODT")
			(pinfunction "PB30A")
			(pintype "bidirectional")
		)
		(pad "T8" smd circle
			(at -0.4 6 180)
			(size 0.45 0.45)
			(layers "F.Cu" "F.Mask" "F.Paste")
			(net 161 "/DDR3/~{DDR3_CAS}")
			(pinfunction "PB30B")
			(pintype "bidirectional")
		)
		(pad "T9" smd circle
			(at 0.4 6 180)
			(size 0.45 0.45)
			(layers "F.Cu" "F.Mask" "F.Paste")
			(net 143 "/DDR3/DDR3_CK_P")
			(pinfunction "PB40A/PCLKT4_1")
			(pintype "bidirectional")
		)
		(pad "T10" smd circle
			(at 1.2 6 180)
			(size 0.45 0.45)
			(layers "F.Cu" "F.Mask" "F.Paste")
			(net 142 "/DDR3/DDR3_CK_N")
			(pinfunction "PB40B/PCLKC4_1")
			(pintype "bidirectional")
		)
		(pad "T11" smd circle
			(at 2 6 180)
			(size 0.45 0.45)
			(layers "F.Cu" "F.Mask" "F.Paste")
			(net 231 "/DDR3/DDR3_DQ15")
			(pinfunction "PB58B/PCLKC3_1/ADC_CN6\n")
			(pintype "bidirectional")
		)
		(pad "T12" smd circle
			(at 2.8 6 180)
			(size 0.45 0.45)
			(layers "F.Cu" "F.Mask" "F.Paste")
			(net 238 "/DDR3/DDR3_DQ9")
			(pinfunction "PB58A/PCLKT3_1/ADC_CP6\n")
			(pintype "bidirectional")
		)
		(pad "T13" smd circle
			(at 3.6 6 180)
			(size 0.45 0.45)
			(layers "F.Cu" "F.Mask" "F.Paste")
			(net 239 "/DDR3/DDR3_UDQS_N")
			(pinfunction "PB60B/ADC_CN9")
			(pintype "bidirectional")
		)
		(pad "T14" smd circle
			(at 4.4 6 180)
			(size 0.45 0.45)
			(layers "F.Cu" "F.Mask" "F.Paste")
			(net 230 "/DDR3/DDR3_UDM")
			(pinfunction "PB66A/COMP1IP")
			(pintype "bidirectional")
		)
		(pad "T15" smd circle
			(at 5.2 6 180)
			(size 0.45 0.45)
			(layers "F.Cu" "F.Mask" "F.Paste")
			(net 237 "/DDR3/DDR3_DQ10")
			(pinfunction "PB66B/COMP1IN")
			(pintype "bidirectional")
		)
		(pad "T16" smd circle
			(at 6 6 180)
			(size 0.45 0.45)
			(layers "F.Cu" "F.Mask" "F.Paste")
			(net 1 "GND")
			(pinfunction "VSS")
			(pintype "passive")
		)
	)
)
